FILE_TYPE = MACRO_DRAWING;
SET COLOR_WIRE YELLOW;
SET COLOR_PROP ORANGE;
SET COLOR_DOT WHITE;
SET COLOR_ARC YELLOW;
SET COLOR_BODY GREEN;
SET COLOR_NOTE PURPLE;
SET PROP_DISPLAY VALUE;
SET PAGE_NUMBER P366;
FORCEADD QUANTA_TITLE_BLOCK_C..1
(4850 2650);
FORCEPROP 1 LAST Q_TITLE Blank
J 0
(-4466 2701);
DISPLAY 2.446809 (-4466 2701);
PAINT GREEN (-4466 2701);
FORCEPROP 2 LAST CUSTOM_TXT_CDS <Q_REV>
J 0
(4666 2753);
DISPLAY 1.212766 (4666 2753);
FORCEPROP 2 LAST CUSTOM_TXT_CDS <NAME_1>
J 0
(1675 2825);
FORCEPROP 2 LAST CUSTOM_TXT_CDS <NAME_2>
J 0
(1675 2700);
FORCEPROP 2 LAST CUSTOM_TXT_CDS <Q_NUMBER>
J 0
(3447 2753);
DISPLAY 1.212766 (3447 2753);
FORCEPROP 2 LAST CUSTOM_TXT_CDS <Q_PROJ>
J 0
(2468 2752);
DISPLAY 1.212766 (2468 2752);
FORCEPROP 2 LAST CUSTOM_TXT_CDS <CON_PAGE_NUM> OF <CON_TOTAL_PAGES>
J 0
(4404 2668);
DISPLAY 0.978723 (4404 2668);
FORCEPROP 2 LAST CUSTOM_TXT_CDS <CON_LAST_MODIFIED>
J 0
(2965 2665);
DISPLAY 0.978723 (2965 2665);
FORCEPROP 2 LAST CDS_LIB pure_quanta
J 0
(4850 2650);
DISPLAY INVISIBLE (4850 2650);
FORCEPROP 1 LAST CDS_LMAN_SYM_OUTLINE -9475,6775,100,-125
J 0
(4850 2650);
DISPLAY 0.468085 (4850 2650);
PAINT GREEN (4850 2650);
DISPLAY INVISIBLE (4850 2650);
FORCEPROP 2 LAST PAGE_BORDER TRUE
J 0
(-3040 7900);
DISPLAY 0.638298 (-3040 7900);
PAINT PINK (-3040 7900);
DISPLAY INVISIBLE (-3040 7900);
FORCEPROP 2 LAST CDS_XR_PAGE_TITLE CR-244 : @T6G_MB_LIB.T6G(SCH_1):PAGE244
J 0
(-3040 7900);
DISPLAY 0.638298 (-3040 7900);
PAINT PINK (-3040 7900);
DISPLAY INVISIBLE (-3040 7900);
FORCEPROP 2 LAST CUSTOM_TXT_CDS <XR_PAGE_TITLE>
J 0
(-3040 7900);
DISPLAY 0.638298 (-3040 7900);
PAINT PINK (-3040 7900);
DISPLAY INVISIBLE (-3040 7900);
FORCEPROP 1 LAST COMMENT_BODY TRUE
J 0
(4862 2637);
DISPLAY 0.978723 (4862 2637);
PAINT GREEN (4862 2637);
DISPLAY INVISIBLE (4862 2637);
FORCEPROP 1 LAST Q_DEPT BU9
J 1
(1087 2699);
DISPLAY 1.957447 (1087 2699);
PAINT GREEN (1087 2699);
DISPLAY INVISIBLE (1087 2699);
FORCEPROP 0 LAST CDS_CON_LAST_MODIFIED Thu Aug 24 10:15:40 2023
J 0
(2965 2665);
DISPLAY INVISIBLE (2965 2665);
QUIT
